(kicad_pcb
	(version 20221018)
	(generator pcbnew)
	(general
    (thickness 1.7403)
  )
	(paper "A4")
	(title_block
    (title "Data Center RDIMM DDR4 Tester")
    (date "2024-09-30")
    (rev "1.2.4")
		(comment 9 "footprint 571 of 690 (J5), pads 321-404 of 404")
	)
	(layers
    (0 "F.Cu" signal)
    (1 "In1.Cu" power)
    (2 "In2.Cu" signal)
    (3 "In3.Cu" power)
    (4 "In4.Cu" power)
    (5 "In5.Cu" signal)
    (6 "In6.Cu" power)
    (7 "In7.Cu" signal)
    (8 "In8.Cu" power)
    (9 "In9.Cu" signal)
    (10 "In10.Cu" power)
    (31 "B.Cu" signal)
    (32 "B.Adhes" user "B.Adhesive")
    (33 "F.Adhes" user "F.Adhesive")
    (34 "B.Paste" user)
    (35 "F.Paste" user)
    (36 "B.SilkS" user "B.Silkscreen")
    (37 "F.SilkS" user "F.Silkscreen")
    (38 "B.Mask" user)
    (39 "F.Mask" user)
    (40 "Dwgs.User" user "User.Drawings")
    (41 "Cmts.User" user "User.Comments")
    (42 "Eco1.User" user "User.Eco1")
    (43 "Eco2.User" user "User.Eco2")
    (44 "Edge.Cuts" user)
    (45 "Margin" user)
    (46 "B.CrtYd" user "B.Courtyard")
    (47 "F.CrtYd" user "F.Courtyard")
    (48 "B.Fab" user)
    (49 "F.Fab" user)
  )
	(footprint "data-center-rdimm-ddr4-tester-footprints:FMC_SAMTEC_ASP-134486-01"
    (layer "B.Cu")
    (at 251 100 90)
    (descr "VITA 57.1 FMC – SEARAY™ HPC")
    (property "Author" "Antmicro")
    (property "License" "Apache-2.0")
    (property "MPN" "ASP-134486-01")
    (property "Manufacturer" "Samtec")
    (property "Sheetfile" "fmc_hpc.kicad_sch")
    (property "Sheetname" "FMC HPC")
    (property "ki_description" "400-pole 10-row 1.27mm Female FMC HPC Connector with gold-plated copper alloy contacts. ")
    (attr smd)
    (fp_text reference "J5" (at -28.4 4.01 270) (layer "B.SilkS")
        (effects (font (size 0.7 0.7) (thickness 0.15)) (justify left bottom mirror))
    )
    (fp_text value "ASP-134486-01" (at 0 -7.9 270) (layer "B.Fab") hide
        (effects (font (size 0.7 0.7) (thickness 0.15)) (justify left bottom mirror))
    )
    (pad "H37" smd circle (at 20.954 -3.174 270) (size 0.64 0.64) (layers "B.Cu" "B.Mask")
      (net 511 "unconnected-(J5B-LA32+-PadH37)") (pinfunction "LA32+") (pintype "passive+no_connect"))
    (pad "H38" smd circle (at 22.225 -3.174 270) (size 0.64 0.64) (layers "B.Cu" "B.Mask")
      (net 519 "unconnected-(J5B-LA32--PadH38)") (pinfunction "LA32-") (pintype "passive+no_connect"))
    (pad "H39" smd circle (at 23.495 -3.174 270) (size 0.64 0.64) (layers "B.Cu" "B.Mask")
      (net 9 "GND") (pinfunction "GND") (pintype "passive"))
    (pad "H40" smd circle (at 24.765 -3.174 270) (size 0.64 0.64) (layers "B.Cu" "B.Mask")
      (net 520 "unconnected-(J5B-VADJ-PadH40)") (pinfunction "VADJ") (pintype "passive+no_connect"))
    (pad "J1" smd circle (at -24.766 -4.445 270) (size 0.64 0.64) (layers "B.Cu" "B.Mask")
      (net 9 "GND") (pinfunction "GND") (pintype "passive"))
    (pad "J2" smd circle (at -23.496 -4.445 270) (size 0.64 0.64) (layers "B.Cu" "B.Mask")
      (net 899 "/FMC HPC/GTR_REFCLK3_R_P") (pinfunction "CLK3_{BIDIR}+") (pintype "passive"))
    (pad "J3" smd circle (at -22.226 -4.445 270) (size 0.64 0.64) (layers "B.Cu" "B.Mask")
      (net 900 "/FMC HPC/GTR_REFCLK3_R_N") (pinfunction "CLK3_{BIDIR}-") (pintype "passive"))
    (pad "J4" smd circle (at -20.955 -4.445 270) (size 0.64 0.64) (layers "B.Cu" "B.Mask")
      (net 9 "GND") (pinfunction "GND") (pintype "passive"))
    (pad "J5" smd circle (at -19.685 -4.445 270) (size 0.64 0.64) (layers "B.Cu" "B.Mask")
      (net 9 "GND") (pinfunction "GND") (pintype "passive"))
    (pad "J6" smd circle (at -18.415 -4.445 270) (size 0.64 0.64) (layers "B.Cu" "B.Mask")
      (net 521 "unconnected-(J5A-HA03+-PadJ6)") (pinfunction "HA03+") (pintype "passive+no_connect"))
    (pad "J7" smd circle (at -17.145 -4.445 270) (size 0.64 0.64) (layers "B.Cu" "B.Mask")
      (net 522 "unconnected-(J5A-HA03--PadJ7)") (pinfunction "HA03-") (pintype "passive+no_connect"))
    (pad "J8" smd circle (at -15.875 -4.445 270) (size 0.64 0.64) (layers "B.Cu" "B.Mask")
      (net 9 "GND") (pinfunction "GND") (pintype "passive"))
    (pad "J9" smd circle (at -14.606 -4.445 270) (size 0.64 0.64) (layers "B.Cu" "B.Mask")
      (net 514 "FMC_IO_18_P") (pinfunction "HA07+") (pintype "passive"))
    (pad "J10" smd circle (at -13.336 -4.445 270) (size 0.64 0.64) (layers "B.Cu" "B.Mask")
      (net 493 "FMC_IO_18_N") (pinfunction "HA07-") (pintype "passive"))
    (pad "J11" smd circle (at -12.065 -4.445 270) (size 0.64 0.64) (layers "B.Cu" "B.Mask")
      (net 9 "GND") (pinfunction "GND") (pintype "passive"))
    (pad "J12" smd circle (at -10.795 -4.445 270) (size 0.64 0.64) (layers "B.Cu" "B.Mask")
      (net 816 "FMC_IO_23_P") (pinfunction "HA11+") (pintype "passive"))
    (pad "J13" smd circle (at -9.526 -4.445 270) (size 0.64 0.64) (layers "B.Cu" "B.Mask")
      (net 812 "FMC_IO_23_N") (pinfunction "HA11-") (pintype "passive"))
    (pad "J14" smd circle (at -8.256 -4.445 270) (size 0.64 0.64) (layers "B.Cu" "B.Mask")
      (net 9 "GND") (pinfunction "GND") (pintype "passive"))
    (pad "J15" smd circle (at -6.986 -4.445 270) (size 0.64 0.64) (layers "B.Cu" "B.Mask")
      (net 523 "unconnected-(J5A-HA14+-PadJ15)") (pinfunction "HA14+") (pintype "passive+no_connect"))
    (pad "J16" smd circle (at -5.715 -4.445 270) (size 0.64 0.64) (layers "B.Cu" "B.Mask")
      (net 527 "unconnected-(J5A-HA14--PadJ16)") (pinfunction "HA14-") (pintype "passive+no_connect"))
    (pad "J17" smd circle (at -4.446 -4.445 270) (size 0.64 0.64) (layers "B.Cu" "B.Mask")
      (net 9 "GND") (pinfunction "GND") (pintype "passive"))
    (pad "J18" smd circle (at -3.175 -4.445 270) (size 0.64 0.64) (layers "B.Cu" "B.Mask")
      (net 428 "FMC_IO_5_P") (pinfunction "HA18+") (pintype "passive"))
    (pad "J19" smd circle (at -1.905 -4.445 270) (size 0.64 0.64) (layers "B.Cu" "B.Mask")
      (net 435 "FMC_IO_5_N") (pinfunction "HA18-") (pintype "passive"))
    (pad "J20" smd circle (at -0.635 -4.445 270) (size 0.64 0.64) (layers "B.Cu" "B.Mask")
      (net 9 "GND") (pinfunction "GND") (pintype "passive"))
    (pad "J21" smd circle (at 0.634 -4.445 270) (size 0.64 0.64) (layers "B.Cu" "B.Mask")
      (net 472 "FMC_IO_12_P") (pinfunction "HA22+") (pintype "passive"))
    (pad "J22" smd circle (at 1.904 -4.445 270) (size 0.64 0.64) (layers "B.Cu" "B.Mask")
      (net 457 "FMC_IO_12_N") (pinfunction "HA22-") (pintype "passive"))
    (pad "J23" smd circle (at 3.174 -4.445 270) (size 0.64 0.64) (layers "B.Cu" "B.Mask")
      (net 9 "GND") (pinfunction "GND") (pintype "passive"))
    (pad "J24" smd circle (at 4.445 -4.445 270) (size 0.64 0.64) (layers "B.Cu" "B.Mask")
      (net 506 "FMC_IO_14_P") (pinfunction "HB01+") (pintype "passive"))
    (pad "J25" smd circle (at 5.714 -4.445 270) (size 0.64 0.64) (layers "B.Cu" "B.Mask")
      (net 507 "FMC_IO_14_N") (pinfunction "HB01-") (pintype "passive"))
    (pad "J26" smd circle (at 6.985 -4.445 270) (size 0.64 0.64) (layers "B.Cu" "B.Mask")
      (net 9 "GND") (pinfunction "GND") (pintype "passive"))
    (pad "J27" smd circle (at 8.255 -4.445 270) (size 0.64 0.64) (layers "B.Cu" "B.Mask")
      (net 811 "FMC_IO_24_P") (pinfunction "HB07+") (pintype "passive"))
    (pad "J28" smd circle (at 9.525 -4.445 270) (size 0.64 0.64) (layers "B.Cu" "B.Mask")
      (net 809 "FMC_IO_24_N") (pinfunction "HB07-") (pintype "passive"))
    (pad "J29" smd circle (at 10.794 -4.445 270) (size 0.64 0.64) (layers "B.Cu" "B.Mask")
      (net 9 "GND") (pinfunction "GND") (pintype "passive"))
    (pad "J30" smd circle (at 12.064 -4.445 270) (size 0.64 0.64) (layers "B.Cu" "B.Mask")
      (net 530 "unconnected-(J5A-HB11+-PadJ30)") (pinfunction "HB11+") (pintype "passive+no_connect"))
    (pad "J31" smd circle (at 13.335 -4.445 270) (size 0.64 0.64) (layers "B.Cu" "B.Mask")
      (net 531 "unconnected-(J5A-HB11--PadJ31)") (pinfunction "HB11-") (pintype "passive+no_connect"))
    (pad "J32" smd circle (at 14.605 -4.445 270) (size 0.64 0.64) (layers "B.Cu" "B.Mask")
      (net 9 "GND") (pinfunction "GND") (pintype "passive"))
    (pad "J33" smd circle (at 15.874 -4.445 270) (size 0.64 0.64) (layers "B.Cu" "B.Mask")
      (net 532 "unconnected-(J5A-HB15+-PadJ33)") (pinfunction "HB15+") (pintype "passive+no_connect"))
    (pad "J34" smd circle (at 17.144 -4.445 270) (size 0.64 0.64) (layers "B.Cu" "B.Mask")
      (net 533 "unconnected-(J5A-HB15--PadJ34)") (pinfunction "HB15-") (pintype "passive+no_connect"))
    (pad "J35" smd circle (at 18.414 -4.445 270) (size 0.64 0.64) (layers "B.Cu" "B.Mask")
      (net 9 "GND") (pinfunction "GND") (pintype "passive"))
    (pad "J36" smd circle (at 19.684 -4.445 270) (size 0.64 0.64) (layers "B.Cu" "B.Mask")
      (net 534 "unconnected-(J5A-HB18+-PadJ36)") (pinfunction "HB18+") (pintype "passive+no_connect"))
    (pad "J37" smd circle (at 20.954 -4.445 270) (size 0.64 0.64) (layers "B.Cu" "B.Mask")
      (net 540 "unconnected-(J5A-HB18--PadJ37)") (pinfunction "HB18-") (pintype "passive+no_connect"))
    (pad "J38" smd circle (at 22.225 -4.445 270) (size 0.64 0.64) (layers "B.Cu" "B.Mask")
      (net 9 "GND") (pinfunction "GND") (pintype "passive"))
    (pad "J39" smd circle (at 23.495 -4.445 270) (size 0.64 0.64) (layers "B.Cu" "B.Mask")
      (net 541 "unconnected-(J5A-VIO_{B_M2C}-PadJ39)") (pinfunction "VIO_{B_M2C}") (pintype "passive+no_connect"))
    (pad "J40" smd circle (at 24.765 -4.445 270) (size 0.64 0.64) (layers "B.Cu" "B.Mask")
      (net 9 "GND") (pinfunction "GND") (pintype "passive"))
    (pad "K1" smd circle (at -24.766 -5.714 270) (size 0.64 0.64) (layers "B.Cu" "B.Mask")
      (net 542 "Net-(J5A-VREF_{B_M2C})") (pinfunction "VREF_{B_M2C}") (pintype "passive"))
    (pad "K2" smd circle (at -23.496 -5.714 270) (size 0.64 0.64) (layers "B.Cu" "B.Mask")
      (net 9 "GND") (pinfunction "GND") (pintype "passive"))
    (pad "K3" smd circle (at -22.226 -5.714 270) (size 0.64 0.64) (layers "B.Cu" "B.Mask")
      (net 9 "GND") (pinfunction "GND") (pintype "passive"))
    (pad "K4" smd circle (at -20.955 -5.714 270) (size 0.64 0.64) (layers "B.Cu" "B.Mask")
      (net 903 "/FMC HPC/GTR_REFCLK2_R_P") (pinfunction "CLK2_{BIDIR}+") (pintype "passive"))
    (pad "K5" smd circle (at -19.685 -5.714 270) (size 0.64 0.64) (layers "B.Cu" "B.Mask")
      (net 904 "/FMC HPC/GTR_REFCLK2_R_N") (pinfunction "CLK2_{BIDIR}-") (pintype "passive"))
    (pad "K6" smd circle (at -18.415 -5.714 270) (size 0.64 0.64) (layers "B.Cu" "B.Mask")
      (net 9 "GND") (pinfunction "GND") (pintype "passive"))
    (pad "K7" smd circle (at -17.145 -5.714 270) (size 0.64 0.64) (layers "B.Cu" "B.Mask")
      (net 492 "FMC_IO_16_P") (pinfunction "HA02+") (pintype "passive"))
    (pad "K8" smd circle (at -15.875 -5.714 270) (size 0.64 0.64) (layers "B.Cu" "B.Mask")
      (net 475 "FMC_IO_16_N") (pinfunction "HA02-") (pintype "passive"))
    (pad "K9" smd circle (at -14.606 -5.714 270) (size 0.64 0.64) (layers "B.Cu" "B.Mask")
      (net 9 "GND") (pinfunction "GND") (pintype "passive"))
    (pad "K10" smd circle (at -13.336 -5.714 270) (size 0.64 0.64) (layers "B.Cu" "B.Mask")
      (net 813 "FMC_IO_21_P") (pinfunction "HA06+") (pintype "passive"))
    (pad "K11" smd circle (at -12.065 -5.714 270) (size 0.64 0.64) (layers "B.Cu" "B.Mask")
      (net 814 "FMC_IO_21_N") (pinfunction "HA06-") (pintype "passive"))
    (pad "K12" smd circle (at -10.795 -5.714 270) (size 0.64 0.64) (layers "B.Cu" "B.Mask")
      (net 9 "GND") (pinfunction "GND") (pintype "passive"))
    (pad "K13" smd circle (at -9.526 -5.714 270) (size 0.64 0.64) (layers "B.Cu" "B.Mask")
      (net 543 "unconnected-(J5A-HA10+-PadK13)") (pinfunction "HA10+") (pintype "passive+no_connect"))
    (pad "K14" smd circle (at -8.256 -5.714 270) (size 0.64 0.64) (layers "B.Cu" "B.Mask")
      (net 544 "unconnected-(J5A-HA10--PadK14)") (pinfunction "HA10-") (pintype "passive+no_connect"))
    (pad "K15" smd circle (at -6.986 -5.714 270) (size 0.64 0.64) (layers "B.Cu" "B.Mask")
      (net 9 "GND") (pinfunction "GND") (pintype "passive"))
    (pad "K16" smd circle (at -5.715 -5.714 270) (size 0.64 0.64) (layers "B.Cu" "B.Mask")
      (net 474 "FMC_IO_17_P") (pinfunction "HA17_{CC}+") (pintype "passive"))
    (pad "K17" smd circle (at -4.446 -5.714 270) (size 0.64 0.64) (layers "B.Cu" "B.Mask")
      (net 459 "FMC_IO_17_N") (pinfunction "HA17_{CC}-") (pintype "passive"))
    (pad "K18" smd circle (at -3.175 -5.714 270) (size 0.64 0.64) (layers "B.Cu" "B.Mask")
      (net 9 "GND") (pinfunction "GND") (pintype "passive"))
    (pad "K19" smd circle (at -1.905 -5.714 270) (size 0.64 0.64) (layers "B.Cu" "B.Mask")
      (net 458 "FMC_IO_13_P") (pinfunction "HA21+") (pintype "passive"))
    (pad "K20" smd circle (at -0.635 -5.714 270) (size 0.64 0.64) (layers "B.Cu" "B.Mask")
      (net 445 "FMC_IO_13_N") (pinfunction "HA21-") (pintype "passive"))
    (pad "K21" smd circle (at 0.634 -5.714 270) (size 0.64 0.64) (layers "B.Cu" "B.Mask")
      (net 9 "GND") (pinfunction "GND") (pintype "passive"))
    (pad "K22" smd circle (at 1.904 -5.714 270) (size 0.64 0.64) (layers "B.Cu" "B.Mask")
      (net 491 "FMC_IO_11_P") (pinfunction "HA23+") (pintype "passive"))
    (pad "K23" smd circle (at 3.174 -5.714 270) (size 0.64 0.64) (layers "B.Cu" "B.Mask")
      (net 473 "FMC_IO_11_N") (pinfunction "HA23-") (pintype "passive"))
    (pad "K24" smd circle (at 4.445 -5.714 270) (size 0.64 0.64) (layers "B.Cu" "B.Mask")
      (net 9 "GND") (pinfunction "GND") (pintype "passive"))
    (pad "K25" smd circle (at 5.714 -5.714 270) (size 0.64 0.64) (layers "B.Cu" "B.Mask")
      (net 517 "FMC_IO_20_P") (pinfunction "HB00_{CC}+") (pintype "passive"))
    (pad "K26" smd circle (at 6.985 -5.714 270) (size 0.64 0.64) (layers "B.Cu" "B.Mask")
      (net 518 "FMC_IO_20_N") (pinfunction "HB00_{CC}-") (pintype "passive"))
    (pad "K27" smd circle (at 8.255 -5.714 270) (size 0.64 0.64) (layers "B.Cu" "B.Mask")
      (net 9 "GND") (pinfunction "GND") (pintype "passive"))
    (pad "K28" smd circle (at 9.525 -5.714 270) (size 0.64 0.64) (layers "B.Cu" "B.Mask")
      (net 815 "FMC_IO_25") (pinfunction "HB06_{CC}+") (pintype "passive"))
    (pad "K29" smd circle (at 10.794 -5.714 270) (size 0.64 0.64) (layers "B.Cu" "B.Mask")
      (net 545 "unconnected-(J5A-HB06_{CC}--PadK29)") (pinfunction "HB06_{CC}-") (pintype "passive+no_connect"))
    (pad "K30" smd circle (at 12.064 -5.714 270) (size 0.64 0.64) (layers "B.Cu" "B.Mask")
      (net 9 "GND") (pinfunction "GND") (pintype "passive"))
    (pad "K31" smd circle (at 13.335 -5.714 270) (size 0.64 0.64) (layers "B.Cu" "B.Mask")
      (net 549 "unconnected-(J5A-HB10+-PadK31)") (pinfunction "HB10+") (pintype "passive+no_connect"))
    (pad "K32" smd circle (at 14.605 -5.714 270) (size 0.64 0.64) (layers "B.Cu" "B.Mask")
      (net 550 "unconnected-(J5A-HB10--PadK32)") (pinfunction "HB10-") (pintype "passive+no_connect"))
    (pad "K33" smd circle (at 15.874 -5.714 270) (size 0.64 0.64) (layers "B.Cu" "B.Mask")
      (net 9 "GND") (pinfunction "GND") (pintype "passive"))
    (pad "K34" smd circle (at 17.144 -5.714 270) (size 0.64 0.64) (layers "B.Cu" "B.Mask")
      (net 551 "unconnected-(J5A-HB14+-PadK34)") (pinfunction "HB14+") (pintype "passive+no_connect"))
    (pad "K35" smd circle (at 18.414 -5.714 270) (size 0.64 0.64) (layers "B.Cu" "B.Mask")
      (net 552 "unconnected-(J5A-HB14--PadK35)") (pinfunction "HB14-") (pintype "passive+no_connect"))
    (pad "K36" smd circle (at 19.684 -5.714 270) (size 0.64 0.64) (layers "B.Cu" "B.Mask")
      (net 9 "GND") (pinfunction "GND") (pintype "passive"))
    (pad "K37" smd circle (at 20.954 -5.714 270) (size 0.64 0.64) (layers "B.Cu" "B.Mask")
      (net 553 "unconnected-(J5A-HB17_{CC}+-PadK37)") (pinfunction "HB17_{CC}+") (pintype "passive+no_connect"))
    (pad "K38" smd circle (at 22.225 -5.714 270) (size 0.64 0.64) (layers "B.Cu" "B.Mask")
      (net 554 "unconnected-(J5A-HB17_{CC}--PadK38)") (pinfunction "HB17_{CC}-") (pintype "passive+no_connect"))
    (pad "K39" smd circle (at 23.495 -5.714 270) (size 0.64 0.64) (layers "B.Cu" "B.Mask")
      (net 9 "GND") (pinfunction "GND") (pintype "passive"))
    (pad "K40" smd circle (at 24.765 -5.714 270) (size 0.64 0.64) (layers "B.Cu" "B.Mask")
      (net 555 "unconnected-(J5A-VIO_{B_M2C}-PadK40)") (pinfunction "VIO_{B_M2C}") (pintype "passive+no_connect"))
  )
)
